(kicad_pcb
	(version 20260206)
	(generator "pcbnew")
	(generator_version "10.0")
	(general
		(thickness 1.6)
		(legacy_teardrops no)
	)
	(paper "A4")
	(title_block
		(title "Bryce Canyon_F.DPB_16315-1-OCP.brd")
		(comment 1 "Bryce Canyon / footprints 1312-1319 of 2223")
	)
	(layers
		(0 "F.Cu" signal "TOP")
		(4 "In1.Cu" signal "L2GND")
		(6 "In2.Cu" signal "L3")
		(8 "In3.Cu" signal "L4GND")
		(10 "In4.Cu" signal "L5")
		(12 "In5.Cu" signal "L6VCC")
		(14 "In6.Cu" signal "L7VCC")
		(16 "In7.Cu" signal "L8")
		(18 "In8.Cu" signal "L9GND")
		(20 "In9.Cu" signal "L10")
		(22 "In10.Cu" signal "L11GND")
		(2 "B.Cu" signal "BOTTOM")
		(9 "F.Adhes" user "F.Adhesive")
		(11 "B.Adhes" user "B.Adhesive")
		(13 "F.Paste" user "Package Geometry/Pastemask Top")
		(15 "B.Paste" user "Package Geometry/Pastemask Bottom")
		(5 "F.SilkS" user "Ref Des/Silkscreen Top")
		(7 "B.SilkS" user "Ref Des/Silkscreen Bottom")
		(1 "F.Mask" user "Board Geometry/Soldermask Top")
		(3 "B.Mask" user "Board Geometry/Soldermask Bottom")
		(17 "Dwgs.User" user "User.Drawings")
		(19 "Cmts.User" user "User.Comments")
		(21 "Eco1.User" user "User.Eco1")
		(23 "Eco2.User" user "User.Eco2")
		(25 "Edge.Cuts" user "Board Geometry/Outline")
		(27 "Margin" user)
		(31 "F.CrtYd" user "Package Geometry/Place Bound Top")
		(29 "B.CrtYd" user "Package Geometry/Place Bound Bottom")
		(35 "F.Fab" user "Ref Des/Assembly Top")
		(33 "B.Fab" user "Ref Des/Assembly Bottom")
	)
	(footprint ""
		(layer "F.Cu")
		(at 456.674982 -322.799964)
		(property "Reference" ""
			(at 0 0 0)
			(layer "F.SilkS")
			(hide yes)
			(effects
				(font
					(size 1.27 1.27)
				)
			)
		)
		(property "Value" "*"
			(at -8.398764 -8.057642 0)
			(unlocked yes)
			(layer "F.Fab")
			(hide yes)
			(effects
				(font
					(size 1.016 1.016)
					(thickness 0.1524)
				)
			)
		)
		(duplicate_pad_numbers_are_jumpers no)
		(fp_poly
			(pts
				(arc
					(start 7.3152 0)
					(mid 0 7.3152)
					(end -7.3152 0)
				)
				(arc
					(start -7.3152 -5.9944)
					(mid 0 -13.3096)
					(end 7.3152 -5.9944)
				)
			)
			(stroke
				(width 0)
				(type default)
			)
			(fill no)
			(layer "B.CrtYd")
		)
		(fp_poly
			(pts
				(arc
					(start 7.3152 0)
					(mid 0 7.3152)
					(end -7.3152 0)
				)
				(arc
					(start -7.3152 -5.9944)
					(mid 0 -13.3096)
					(end 7.3152 -5.9944)
				)
			)
			(stroke
				(width 0)
				(type default)
			)
			(fill no)
			(layer "F.CrtYd")
		)
		(fp_poly
			(pts
				(arc
					(start 7.3152 0)
					(mid 0 7.3152)
					(end -7.3152 0)
				)
				(arc
					(start -7.3152 -5.9944)
					(mid 0 -13.3096)
					(end 7.3152 -5.9944)
				)
			)
			(stroke
				(width 0)
				(type default)
			)
			(fill no)
			(layer "B.Fab")
		)
		(fp_poly
			(pts
				(arc
					(start 7.3152 0)
					(mid 0 7.3152)
					(end -7.3152 0)
				)
				(arc
					(start -7.3152 -5.9944)
					(mid 0 -13.3096)
					(end 7.3152 -5.9944)
				)
			)
			(stroke
				(width 0)
				(type default)
			)
			(fill no)
			(layer "F.Fab")
		)
		(pad "1" thru_hole oval
			(at 0 0)
			(size 14.0208 20.0152)
			(drill 0.0254
				(offset 0 -2.9972)
			)
			(layers "*.Cu" "*.Mask")
			(remove_unused_layers no)
			(net "Net_38")
			(clearance -1.002284)
			(thermal_gap 0.1524)
			(padstack
				(mode front_inner_back)
				(layer "Inner"
					(shape custom)
					(size 2.928012 2.928012)
					(options
						(anchor circle)
					)
					(primitives
						(gr_poly
							(pts
								(arc
									(start 4.571746 -2.084324)
									(mid 0.000333 7.430372)
									(end -4.571492 -2.084324)
								)
								(arc
									(start -4.571492 -2.084324)
									(mid -3.570296 -3.611977)
									(end -2.875026 -5.30098)
								)
								(arc
									(start -2.875026 -5.30098)
									(mid 0.000217 -7.43089)
									(end 2.87528 -5.30098)
								)
								(arc
									(start 2.87528 -5.30098)
									(mid 3.570511 -3.611956)
									(end 4.571746 -2.084324)
								)
							)
							(width 0)
							(fill yes)
						)
					)
					(clearance 0.1524)
				)
				(layer "B.Cu"
					(shape oval)
					(size 14.0208 20.0152)
					(offset 0 -2.9972)
					(clearance -1.002284)
				)
			)
		)
		(zone
			(layers "F.Cu" "B.Cu" "In1.Cu" "In2.Cu" "In3.Cu" "In4.Cu" "In5.Cu" "In6.Cu"
				"In7.Cu" "In8.Cu" "In9.Cu" "In10.Cu"
			)
			(hatch none 0.5)
			(connect_pads
				(clearance 0)
			)
			(min_thickness 0.25)
			(keepout
				(tracks not_allowed)
				(vias allowed)
				(pads allowed)
				(copperpour not_allowed)
				(footprints allowed)
			)
			(placement
				(enabled no)
				(sheetname "")
			)
			(fill
				(thermal_gap 0.5)
				(thermal_bridge_width 0.5)
				(island_removal_mode 0)
			)
			(polygon
				(pts
					(arc
						(start 449.664582 -328.794364)
						(mid 456.674982 -335.804764)
						(end 463.685382 -328.794364)
					)
					(arc
						(start 463.685382 -322.799964)
						(mid 456.674982 -315.789564)
						(end 449.664582 -322.799964)
					)
				)
			)
		)
	)
	(footprint ""
		(layer "F.Cu")
		(at 430.387252 -160.735518 180)
		(property "Reference" "R630"
			(at 0 0 180)
			(layer "F.SilkS")
			(hide yes)
			(effects
				(font
					(size 1.27 1.27)
				)
			)
		)
		(property "Value" "0R2J-2-GP"
			(at 0.064008 -3.993896 180)
			(unlocked yes)
			(layer "F.Fab")
			(hide yes)
			(effects
				(font
					(size 1.016 1.016)
					(thickness 0.1524)
				)
			)
		)
		(property "Device Type" "R402H16"
			(at 0.064008 -5.517896 180)
			(unlocked yes)
			(layer "F.Fab")
			(hide yes)
			(effects
				(font
					(size 1.016 1.016)
					(thickness 0.1524)
				)
			)
		)
		(duplicate_pad_numbers_are_jumpers no)
		(fp_line
			(start 0.508 -0.9398)
			(end -0.508 -0.9398)
			(stroke
				(width 0.1524)
				(type default)
			)
			(layer "F.SilkS")
		)
		(fp_line
			(start -0.508 -0.9398)
			(end -0.508 0.9398)
			(stroke
				(width 0.1524)
				(type default)
			)
			(layer "F.SilkS")
		)
		(fp_rect
			(start -0.508 0.9398)
			(end 0.508 -0.9398)
			(stroke
				(width 0)
				(type default)
			)
			(fill no)
			(layer "F.CrtYd")
		)
		(fp_rect
			(start -0.508 0.9398)
			(end 0.508 -0.9398)
			(stroke
				(width 0)
				(type default)
			)
			(fill no)
			(layer "F.Fab")
		)
		(pad "1" smd custom
			(at 0 -0.4445 180)
			(size 0.1397 0.1397)
			(layers "F.Cu" "F.Mask" "F.Paste")
			(net "SW_HDD_G21")
			(options
				(clearance outline)
				(anchor circle)
			)
			(primitives
				(gr_poly
					(pts
						(arc
							(start -0.1778 -0.2794)
							(mid -0.249642 -0.249642)
							(end -0.2794 -0.1778)
						)
						(arc
							(start -0.2794 0.1778)
							(mid -0.249642 0.249642)
							(end -0.1778 0.2794)
						)
						(arc
							(start 0.1778 0.2794)
							(mid 0.249642 0.249642)
							(end 0.2794 0.1778)
						)
						(arc
							(start 0.2794 -0.1778)
							(mid 0.249642 -0.249642)
							(end 0.1778 -0.2794)
						)
					)
					(width 0)
					(fill yes)
				)
			)
		)
		(pad "2" smd custom
			(at 0 0.4445 180)
			(size 0.1397 0.1397)
			(layers "F.Cu" "F.Mask" "F.Paste")
			(net "SW_HDD_R21")
			(options
				(clearance outline)
				(anchor circle)
			)
			(primitives
				(gr_poly
					(pts
						(arc
							(start -0.1778 -0.2794)
							(mid -0.249642 -0.249642)
							(end -0.2794 -0.1778)
						)
						(arc
							(start -0.2794 0.1778)
							(mid -0.249642 0.249642)
							(end -0.1778 0.2794)
						)
						(arc
							(start 0.1778 0.2794)
							(mid 0.249642 0.249642)
							(end 0.2794 0.1778)
						)
						(arc
							(start 0.2794 -0.1778)
							(mid 0.249642 -0.249642)
							(end 0.1778 -0.2794)
						)
					)
					(width 0)
					(fill yes)
				)
			)
		)
	)
	(footprint ""
		(layer "F.Cu")
		(at 461.9371 -45.735494 180)
		(property "Reference" "R929"
			(at 0 0 180)
			(layer "F.SilkS")
			(hide yes)
			(effects
				(font
					(size 1.27 1.27)
				)
			)
		)
		(property "Value" "0R2J-2-GP"
			(at 0.064008 -3.993896 180)
			(unlocked yes)
			(layer "F.Fab")
			(hide yes)
			(effects
				(font
					(size 1.016 1.016)
					(thickness 0.1524)
				)
			)
		)
		(property "Device Type" "R402H16"
			(at 0.064008 -5.517896 180)
			(unlocked yes)
			(layer "F.Fab")
			(hide yes)
			(effects
				(font
					(size 1.016 1.016)
					(thickness 0.1524)
				)
			)
		)
		(duplicate_pad_numbers_are_jumpers no)
		(fp_line
			(start 0.508 -0.9398)
			(end -0.508 -0.9398)
			(stroke
				(width 0.1524)
				(type default)
			)
			(layer "F.SilkS")
		)
		(fp_line
			(start -0.508 -0.9398)
			(end -0.508 0.9398)
			(stroke
				(width 0.1524)
				(type default)
			)
			(layer "F.SilkS")
		)
		(fp_rect
			(start -0.508 0.9398)
			(end 0.508 -0.9398)
			(stroke
				(width 0)
				(type default)
			)
			(fill no)
			(layer "F.CrtYd")
		)
		(fp_rect
			(start -0.508 0.9398)
			(end 0.508 -0.9398)
			(stroke
				(width 0)
				(type default)
			)
			(fill no)
			(layer "F.Fab")
		)
		(pad "1" smd custom
			(at 0 -0.4445 180)
			(size 0.1397 0.1397)
			(layers "F.Cu" "F.Mask" "F.Paste")
			(net "SW_HDD_G34")
			(options
				(clearance outline)
				(anchor circle)
			)
			(primitives
				(gr_poly
					(pts
						(arc
							(start -0.1778 -0.2794)
							(mid -0.249642 -0.249642)
							(end -0.2794 -0.1778)
						)
						(arc
							(start -0.2794 0.1778)
							(mid -0.249642 0.249642)
							(end -0.1778 0.2794)
						)
						(arc
							(start 0.1778 0.2794)
							(mid 0.249642 0.249642)
							(end 0.2794 0.1778)
						)
						(arc
							(start 0.2794 -0.1778)
							(mid 0.249642 -0.249642)
							(end 0.1778 -0.2794)
						)
					)
					(width 0)
					(fill yes)
				)
			)
		)
		(pad "2" smd custom
			(at 0 0.4445 180)
			(size 0.1397 0.1397)
			(layers "F.Cu" "F.Mask" "F.Paste")
			(net "SW_HDD_R34")
			(options
				(clearance outline)
				(anchor circle)
			)
			(primitives
				(gr_poly
					(pts
						(arc
							(start -0.1778 -0.2794)
							(mid -0.249642 -0.249642)
							(end -0.2794 -0.1778)
						)
						(arc
							(start -0.2794 0.1778)
							(mid -0.249642 0.249642)
							(end -0.1778 0.2794)
						)
						(arc
							(start 0.1778 0.2794)
							(mid 0.249642 0.249642)
							(end 0.2794 0.1778)
						)
						(arc
							(start 0.2794 -0.1778)
							(mid 0.249642 -0.249642)
							(end 0.1778 -0.2794)
						)
					)
					(width 0)
					(fill yes)
				)
			)
		)
	)
	(footprint ""
		(layer "F.Cu")
		(at 164.964364 -294.84574 90)
		(property "Reference" "R573"
			(at 0 0 90)
			(layer "F.SilkS")
			(hide yes)
			(effects
				(font
					(size 1.27 1.27)
				)
			)
		)
		(property "Value" "4K7R2J-2-GP"
			(at 0.064008 -3.993896 90)
			(unlocked yes)
			(layer "F.Fab")
			(hide yes)
			(effects
				(font
					(size 1.016 1.016)
					(thickness 0.1524)
				)
			)
		)
		(property "Device Type" "R402H16"
			(at 0.064008 -5.517896 90)
			(unlocked yes)
			(layer "F.Fab")
			(hide yes)
			(effects
				(font
					(size 1.016 1.016)
					(thickness 0.1524)
				)
			)
		)
		(duplicate_pad_numbers_are_jumpers no)
		(fp_line
			(start 0.508 -0.9398)
			(end -0.508 -0.9398)
			(stroke
				(width 0.1524)
				(type default)
			)
			(layer "F.SilkS")
		)
		(fp_line
			(start -0.508 -0.9398)
			(end -0.508 0.9398)
			(stroke
				(width 0.1524)
				(type default)
			)
			(layer "F.SilkS")
		)
		(fp_rect
			(start -0.508 0.9398)
			(end 0.508 -0.9398)
			(stroke
				(width 0)
				(type default)
			)
			(fill no)
			(layer "F.CrtYd")
		)
		(fp_rect
			(start -0.508 0.9398)
			(end 0.508 -0.9398)
			(stroke
				(width 0)
				(type default)
			)
			(fill no)
			(layer "F.Fab")
		)
		(pad "1" smd custom
			(at 0 -0.4445 90)
			(size 0.1397 0.1397)
			(layers "F.Cu" "F.Mask" "F.Paste")
			(net "DRIVE_B_29_ACT")
			(options
				(clearance outline)
				(anchor circle)
			)
			(primitives
				(gr_poly
					(pts
						(arc
							(start -0.1778 -0.2794)
							(mid -0.249642 -0.249642)
							(end -0.2794 -0.1778)
						)
						(arc
							(start -0.2794 0.1778)
							(mid -0.249642 0.249642)
							(end -0.1778 0.2794)
						)
						(arc
							(start 0.1778 0.2794)
							(mid 0.249642 0.249642)
							(end 0.2794 0.1778)
						)
						(arc
							(start 0.2794 -0.1778)
							(mid 0.249642 -0.249642)
							(end 0.1778 -0.2794)
						)
					)
					(width 0)
					(fill yes)
				)
			)
		)
		(pad "2" smd custom
			(at 0 0.4445 90)
			(size 0.1397 0.1397)
			(layers "F.Cu" "F.Mask" "F.Paste")
			(net "GND")
			(options
				(clearance outline)
				(anchor circle)
			)
			(primitives
				(gr_poly
					(pts
						(arc
							(start -0.1778 -0.2794)
							(mid -0.249642 -0.249642)
							(end -0.2794 -0.1778)
						)
						(arc
							(start -0.2794 0.1778)
							(mid -0.249642 0.249642)
							(end -0.1778 0.2794)
						)
						(arc
							(start 0.1778 0.2794)
							(mid 0.249642 0.249642)
							(end 0.2794 0.1778)
						)
						(arc
							(start 0.2794 -0.1778)
							(mid 0.249642 -0.249642)
							(end 0.1778 -0.2794)
						)
					)
					(width 0)
					(fill yes)
				)
			)
		)
	)
	(footprint ""
		(layer "F.Cu")
		(at 471.924126 -52.060094 90)
		(property "Reference" "R942"
			(at 0 0 90)
			(layer "F.SilkS")
			(hide yes)
			(effects
				(font
					(size 1.27 1.27)
				)
			)
		)
		(property "Value" "4K7R2J-2-GP"
			(at 0.064008 -3.993896 90)
			(unlocked yes)
			(layer "F.Fab")
			(hide yes)
			(effects
				(font
					(size 1.016 1.016)
					(thickness 0.1524)
				)
			)
		)
		(property "Device Type" "R402H16"
			(at 0.064008 -5.517896 90)
			(unlocked yes)
			(layer "F.Fab")
			(hide yes)
			(effects
				(font
					(size 1.016 1.016)
					(thickness 0.1524)
				)
			)
		)
		(duplicate_pad_numbers_are_jumpers no)
		(fp_line
			(start 0.508 -0.9398)
			(end -0.508 -0.9398)
			(stroke
				(width 0.1524)
				(type default)
			)
			(layer "F.SilkS")
		)
		(fp_line
			(start -0.508 -0.9398)
			(end -0.508 0.9398)
			(stroke
				(width 0.1524)
				(type default)
			)
			(layer "F.SilkS")
		)
		(fp_rect
			(start -0.508 0.9398)
			(end 0.508 -0.9398)
			(stroke
				(width 0)
				(type default)
			)
			(fill no)
			(layer "F.CrtYd")
		)
		(fp_rect
			(start -0.508 0.9398)
			(end 0.508 -0.9398)
			(stroke
				(width 0)
				(type default)
			)
			(fill no)
			(layer "F.Fab")
		)
		(pad "1" smd custom
			(at 0 -0.4445 90)
			(size 0.1397 0.1397)
			(layers "F.Cu" "F.Mask" "F.Paste")
			(net "P12V_A")
			(options
				(clearance outline)
				(anchor circle)
			)
			(primitives
				(gr_poly
					(pts
						(arc
							(start -0.1778 -0.2794)
							(mid -0.249642 -0.249642)
							(end -0.2794 -0.1778)
						)
						(arc
							(start -0.2794 0.1778)
							(mid -0.249642 0.249642)
							(end -0.1778 0.2794)
						)
						(arc
							(start 0.1778 0.2794)
							(mid 0.249642 0.249642)
							(end 0.2794 0.1778)
						)
						(arc
							(start 0.2794 -0.1778)
							(mid 0.249642 -0.249642)
							(end 0.1778 -0.2794)
						)
					)
					(width 0)
					(fill yes)
				)
			)
		)
		(pad "2" smd custom
			(at 0 0.4445 90)
			(size 0.1397 0.1397)
			(layers "F.Cu" "F.Mask" "F.Paste")
			(net "SW_HDD_P35")
			(options
				(clearance outline)
				(anchor circle)
			)
			(primitives
				(gr_poly
					(pts
						(arc
							(start -0.1778 -0.2794)
							(mid -0.249642 -0.249642)
							(end -0.2794 -0.1778)
						)
						(arc
							(start -0.2794 0.1778)
							(mid -0.249642 0.249642)
							(end -0.1778 0.2794)
						)
						(arc
							(start 0.1778 0.2794)
							(mid 0.249642 0.249642)
							(end 0.2794 0.1778)
						)
						(arc
							(start 0.2794 -0.1778)
							(mid 0.249642 -0.249642)
							(end 0.1778 -0.2794)
						)
					)
					(width 0)
					(fill yes)
				)
			)
		)
	)
	(footprint ""
		(layer "F.Cu")
		(at 272.385028 -11.73353 90)
		(property "Reference" "TP194"
			(at 0 0 90)
			(layer "F.SilkS")
			(hide yes)
			(effects
				(font
					(size 1.27 1.27)
				)
			)
		)
		(property "Value" "TPAD32-GP"
			(at -0.0508 -1.6764 90)
			(unlocked yes)
			(layer "F.Fab")
			(hide yes)
			(effects
				(font
					(size 1.016 1.016)
					(thickness 0.1524)
				)
			)
		)
		(property "Device Type" "TPAD32"
			(at -0.0508 -3.2004 90)
			(unlocked yes)
			(layer "F.Fab")
			(hide yes)
			(effects
				(font
					(size 1.016 1.016)
					(thickness 0.1524)
				)
			)
		)
		(duplicate_pad_numbers_are_jumpers no)
		(fp_poly
			(pts
				(arc
					(start 0 0.4064)
					(mid 0 -0.4064)
					(end 0 0.4064)
				)
			)
			(stroke
				(width 0)
				(type default)
			)
			(fill no)
			(layer "F.CrtYd")
		)
		(fp_poly
			(pts
				(arc
					(start 0 0.7112)
					(mid 0 -0.7112)
					(end 0 0.7112)
				)
			)
			(stroke
				(width 0)
				(type default)
			)
			(fill no)
			(layer "F.Fab")
		)
		(pad "1" smd circle
			(at 0 0 90)
			(size 0.8128 0.8128)
			(layers "F.Cu" "F.Mask" "F.Paste")
			(net "TP_COMP_B_NCSI_TXD1")
		)
	)
	(footprint ""
		(layer "F.Cu")
		(at 32.463486 -273.660616 90)
		(property "Reference" "C507"
			(at 0 0 90)
			(layer "F.SilkS")
			(hide yes)
			(effects
				(font
					(size 1.27 1.27)
				)
			)
		)
		(property "Value" "SCD01U16V1KX-GP"
			(at -2.8321 -1.7399 90)
			(unlocked yes)
			(layer "F.Fab")
			(hide yes)
			(effects
				(font
					(size 1.016 1.016)
					(thickness 0.1524)
				)
			)
		)
		(property "Device Type" "C0201H13"
			(at -2.8321 -3.2639 90)
			(unlocked yes)
			(layer "F.Fab")
			(hide yes)
			(effects
				(font
					(size 1.016 1.016)
					(thickness 0.1524)
				)
			)
		)
		(duplicate_pad_numbers_are_jumpers no)
		(fp_rect
			(start -0.2794 0.6477)
			(end 0.2794 -0.6477)
			(stroke
				(width 0)
				(type default)
			)
			(fill no)
			(layer "F.CrtYd")
		)
		(fp_rect
			(start -0.2794 0.6477)
			(end 0.2794 -0.6477)
			(stroke
				(width 0)
				(type default)
			)
			(fill no)
			(layer "F.Fab")
		)
		(pad "1" smd custom
			(at 0 -0.2794 90)
			(size 0.0762 0.0762)
			(layers "F.Cu" "F.Mask" "F.Paste")
			(net "SAS_HDD_RX_P0")
			(options
				(clearance outline)
				(anchor circle)
			)
			(primitives
				(gr_poly
					(pts
						(arc
							(start 0.1524 -0.127)
							(mid 0.137521 -0.162921)
							(end 0.1016 -0.1778)
						)
						(arc
							(start -0.1016 -0.1778)
							(mid -0.137521 -0.162921)
							(end -0.1524 -0.127)
						)
						(arc
							(start -0.1524 0.127)
							(mid -0.137521 0.162921)
							(end -0.1016 0.1778)
						)
						(arc
							(start 0.1016 0.1778)
							(mid 0.137521 0.162921)
							(end 0.1524 0.127)
						)
					)
					(width 0)
					(fill yes)
				)
			)
		)
		(pad "2" smd custom
			(at 0 0.2794 90)
			(size 0.0762 0.0762)
			(layers "F.Cu" "F.Mask" "F.Paste")
			(net "PHY_SCC_A_TO_DRV_A_0_DP")
			(options
				(clearance outline)
				(anchor circle)
			)
			(primitives
				(gr_poly
					(pts
						(arc
							(start 0.1524 -0.127)
							(mid 0.137521 -0.162921)
							(end 0.1016 -0.1778)
						)
						(arc
							(start -0.1016 -0.1778)
							(mid -0.137521 -0.162921)
							(end -0.1524 -0.127)
						)
						(arc
							(start -0.1524 0.127)
							(mid -0.137521 0.162921)
							(end -0.1016 0.1778)
						)
						(arc
							(start 0.1016 0.1778)
							(mid 0.137521 0.162921)
							(end 0.1524 0.127)
						)
					)
					(width 0)
					(fill yes)
				)
			)
		)
	)
	(footprint ""
		(layer "F.Cu")
		(at 333.502 -73.954894 180)
		(property "Reference" "C436"
			(at 0 0 180)
			(layer "F.SilkS")
			(hide yes)
			(effects
				(font
					(size 1.27 1.27)
				)
			)
		)
		(property "Value" "SC4D7U25V5KX-1-GP"
			(at -0.0762 -6.1214 180)
			(unlocked yes)
			(layer "F.Fab")
			(hide yes)
			(effects
				(font
					(size 1.016 1.016)
					(thickness 0.1524)
				)
			)
		)
		(property "Device Type" "C805H58"
			(at -0.0762 -8.1534 180)
			(unlocked yes)
			(layer "F.Fab")
			(hide yes)
			(effects
				(font
					(size 1.016 1.016)
					(thickness 0.1524)
				)
			)
		)
		(duplicate_pad_numbers_are_jumpers no)
		(fp_line
			(start 0.635 0)
			(end -0.635 0)
			(stroke
				(width 0.508)
				(type default)
			)
			(layer "F.SilkS")
		)
		(fp_rect
			(start -0.9652 1.778)
			(end 0.9652 -1.778)
			(stroke
				(width 0)
				(type default)
			)
			(fill no)
			(layer "F.CrtYd")
		)
		(fp_poly
			(pts
				(xy -0.9652 -1.778) (xy 0.9652 -1.778) (xy 0.9652 1.778) (xy -0.9652 1.778)
			)
			(stroke
				(width 0)
				(type default)
			)
			(fill no)
			(layer "F.Fab")
		)
		(pad "1" smd rect
			(at 0 -0.9652 180)
			(size 1.397 1.143)
			(layers "F.Cu" "F.Mask" "F.Paste")
			(net "P12V_HDD30")
		)
		(pad "2" smd rect
			(at 0 0.9652 180)
			(size 1.397 1.143)
			(layers "F.Cu" "F.Mask" "F.Paste")
			(net "GND")
		)
	)
)
